(kicad_pcb
	(version 20260206)
	(generator "pcbnew")
	(generator_version "10.0")
	(general
		(thickness 1.6)
		(legacy_teardrops no)
	)
	(paper "A4")
	(title_block
		(title "04192023_DAF0TMB3IC0_F0TG_MB_C_brd_V02_OCP.brd")
		(comment 1 "Grand Teton / footprints 4890-4892 of 8354")
	)
	(layers
		(0 "F.Cu" signal "TOP")
		(4 "In1.Cu" signal "GND")
		(6 "In2.Cu" signal "IN1")
		(8 "In3.Cu" signal "GND1")
		(10 "In4.Cu" signal "IN2")
		(12 "In5.Cu" signal "GND2")
		(14 "In6.Cu" signal "IN3")
		(16 "In7.Cu" signal "GND3")
		(18 "In8.Cu" signal "VCC")
		(20 "In9.Cu" signal "VCC1")
		(22 "In10.Cu" signal "GND4")
		(24 "In11.Cu" signal "IN4")
		(26 "In12.Cu" signal "GND5")
		(28 "In13.Cu" signal "IN5")
		(30 "In14.Cu" signal "GND6")
		(32 "In15.Cu" signal "IN6")
		(34 "In16.Cu" signal "GND7")
		(2 "B.Cu" signal "BOTTOM")
		(9 "F.Adhes" user "F.Adhesive")
		(11 "B.Adhes" user "B.Adhesive")
		(13 "F.Paste" user "Package Geometry/Pastemask Top")
		(15 "B.Paste" user "Package Geometry/Pastemask Bottom")
		(5 "F.SilkS" user "Ref Des/Silkscreen Top")
		(7 "B.SilkS" user "Ref Des/Silkscreen Bottom")
		(1 "F.Mask" user "Board Geometry/Soldermask Top")
		(3 "B.Mask" user "Board Geometry/Soldermask Bottom")
		(17 "Dwgs.User" user "User.Drawings")
		(19 "Cmts.User" user "User.Comments")
		(21 "Eco1.User" user "User.Eco1")
		(23 "Eco2.User" user "User.Eco2")
		(25 "Edge.Cuts" user "Board Geometry/Outline")
		(27 "Margin" user)
		(31 "F.CrtYd" user "Package Geometry/Place Bound Top")
		(29 "B.CrtYd" user "Package Geometry/Place Bound Bottom")
		(35 "F.Fab" user "Ref Des/Assembly Top")
		(33 "B.Fab" user "Ref Des/Assembly Bottom")
	)
	(footprint ""
		(layer "F.Cu")
		(at 310.134 -360.68 -90)
		(property "Reference" "PU12"
			(at -6.05409 1.856232 0)
			(unlocked yes)
			(layer "F.SilkS")
			(effects
				(font
					(size 0.7874 0.5842)
					(thickness 0.1524)
				)
			)
		)
		(property "Value" ""
			(at 0 0 270)
			(layer "F.Fab")
			(effects
				(font
					(size 1.27 1.27)
				)
			)
		)
		(duplicate_pad_numbers_are_jumpers no)
		(fp_line
			(start -3.024886 3.024886)
			(end -3.024886 2.428494)
			(stroke
				(width 0.1524)
				(type default)
			)
			(layer "F.SilkS")
		)
		(fp_line
			(start -2.428494 3.024886)
			(end -3.024886 3.024886)
			(stroke
				(width 0.1524)
				(type default)
			)
			(layer "F.SilkS")
		)
		(fp_line
			(start 3.024886 3.024886)
			(end 2.428494 3.024886)
			(stroke
				(width 0.1524)
				(type default)
			)
			(layer "F.SilkS")
		)
		(fp_line
			(start 3.024886 2.428494)
			(end 3.024886 3.024886)
			(stroke
				(width 0.1524)
				(type default)
			)
			(layer "F.SilkS")
		)
		(fp_line
			(start -3.024886 -2.428494)
			(end -3.024886 -3.024886)
			(stroke
				(width 0.1524)
				(type default)
			)
			(layer "F.SilkS")
		)
		(fp_line
			(start -3.024886 -3.024886)
			(end -2.428494 -3.024886)
			(stroke
				(width 0.1524)
				(type default)
			)
			(layer "F.SilkS")
		)
		(fp_line
			(start 2.428494 -3.024886)
			(end 3.024886 -3.024886)
			(stroke
				(width 0.1524)
				(type default)
			)
			(layer "F.SilkS")
		)
		(fp_line
			(start 3.024886 -3.024886)
			(end 3.024886 -2.428494)
			(stroke
				(width 0.1524)
				(type default)
			)
			(layer "F.SilkS")
		)
		(fp_poly
			(pts
				(xy -4.832096 -2.695448) (xy -4.832096 -1.679448) (xy -3.816096 -2.187448)
			)
			(stroke
				(width 0)
				(type default)
			)
			(fill yes)
			(layer "F.SilkS")
		)
		(fp_line
			(start -3.024886 3.024886)
			(end -3.024886 -3.024886)
			(stroke
				(width 0.1)
				(type default)
			)
			(layer "F.Fab")
		)
		(fp_line
			(start 3.024886 3.024886)
			(end -3.024886 3.024886)
			(stroke
				(width 0.1)
				(type default)
			)
			(layer "F.Fab")
		)
		(fp_line
			(start -3.024886 -3.024886)
			(end 3.024886 -3.024886)
			(stroke
				(width 0.1)
				(type default)
			)
			(layer "F.Fab")
		)
		(fp_line
			(start 3.024886 -3.024886)
			(end 3.024886 3.024886)
			(stroke
				(width 0.1)
				(type default)
			)
			(layer "F.Fab")
		)
		(fp_poly
			(pts
				(xy -3.332226 -2.199894) (xy -4.348226 -1.691894) (xy -4.348226 -2.707894)
			)
			(stroke
				(width 0)
				(type default)
			)
			(fill yes)
			(layer "F.Fab")
		)
		(pad "1" smd rect
			(at -2.875026 -2.199894 180)
			(size 0.1778 0.6604)
			(layers "F.Cu" "F.Mask" "F.Paste")
			(net "PVDDIO_P0_PWM1")
		)
		(pad "2" smd rect
			(at -2.875026 -1.800098 180)
			(size 0.1778 0.6604)
			(layers "F.Cu" "F.Mask" "F.Paste")
			(net "PVDDIO_P0_PWM2")
		)
		(pad "3" smd rect
			(at -2.875026 -1.400048 180)
			(size 0.1778 0.6604)
			(layers "F.Cu" "F.Mask" "F.Paste")
			(net "PVDDIO_P0_PWM3")
		)
		(pad "4" smd rect
			(at -2.875026 -0.999998 180)
			(size 0.1778 0.6604)
			(layers "F.Cu" "F.Mask" "F.Paste")
			(net "PVDDIO_P0_PWM4")
		)
		(pad "5" smd rect
			(at -2.875026 -0.599948 180)
			(size 0.1778 0.6604)
			(layers "F.Cu" "F.Mask" "F.Paste")
			(net "NC_PVDDCR_CPU1_P0_PWM8")
		)
		(pad "6" smd rect
			(at -2.875026 -0.199898 180)
			(size 0.1778 0.6604)
			(layers "F.Cu" "F.Mask" "F.Paste")
			(net "NC_PVDDCR_CPU1_P0_PWM7")
		)
		(pad "7" smd rect
			(at -2.875026 0.199898 180)
			(size 0.1778 0.6604)
			(layers "F.Cu" "F.Mask" "F.Paste")
			(net "PVDDCR_CPU1_P0_PWM6")
		)
		(pad "8" smd rect
			(at -2.875026 0.599948 180)
			(size 0.1778 0.6604)
			(layers "F.Cu" "F.Mask" "F.Paste")
			(net "PVDDCR_CPU1_P0_PWM5")
		)
		(pad "9" smd rect
			(at -2.875026 0.999998 180)
			(size 0.1778 0.6604)
			(layers "F.Cu" "F.Mask" "F.Paste")
			(net "PVDDCR_CPU1_P0_PWM4")
		)
		(pad "10" smd rect
			(at -2.875026 1.400048 180)
			(size 0.1778 0.6604)
			(layers "F.Cu" "F.Mask" "F.Paste")
			(net "PVDDCR_CPU1_P0_PWM3")
		)
		(pad "11" smd rect
			(at -2.875026 1.800098 180)
			(size 0.1778 0.6604)
			(layers "F.Cu" "F.Mask" "F.Paste")
			(net "PVDDCR_CPU1_P0_PWM2")
		)
		(pad "12" smd rect
			(at -2.875026 2.199894 180)
			(size 0.1778 0.6604)
			(layers "F.Cu" "F.Mask" "F.Paste")
			(net "PVDDCR_CPU1_P0_PWM1")
		)
		(pad "13" smd rect
			(at -2.199894 2.875026 270)
			(size 0.1778 0.6604)
			(layers "F.Cu" "F.Mask" "F.Paste")
			(net "SMB_DIO_PVDDCR_CPU1_P0_R")
		)
		(pad "14" smd rect
			(at -1.800098 2.875026 270)
			(size 0.1778 0.6604)
			(layers "F.Cu" "F.Mask" "F.Paste")
			(net "SMB_CLK_PVDDCR_CPU1_P0_R")
		)
		(pad "15" smd rect
			(at -1.400048 2.875026 270)
			(size 0.1778 0.6604)
			(layers "F.Cu" "F.Mask" "F.Paste")
			(net "PVDDCR_CPU1_P0_SMB_ALERT_R")
		)
		(pad "16" smd rect
			(at -0.999998 2.875026 270)
			(size 0.1778 0.6604)
			(layers "F.Cu" "F.Mask" "F.Paste")
			(net "PWRGD_PVDDCR_CPU1_P0_R")
		)
		(pad "17" smd rect
			(at -0.599948 2.875026 270)
			(size 0.1778 0.6604)
			(layers "F.Cu" "F.Mask" "F.Paste")
			(net "PVDDCR_CPU1_P0_EN_R")
		)
		(pad "18" smd rect
			(at -0.199898 2.875026 270)
			(size 0.1778 0.6604)
			(layers "F.Cu" "F.Mask" "F.Paste")
			(net "PVDDCR_CPU1_P0_RESET_N_R")
		)
		(pad "19" smd rect
			(at 0.199898 2.875026 270)
			(size 0.1778 0.6604)
			(layers "F.Cu" "F.Mask" "F.Paste")
			(net "PVDD18_S5_P0")
		)
		(pad "20" smd rect
			(at 0.599948 2.875026 270)
			(size 0.1778 0.6604)
			(layers "F.Cu" "F.Mask" "F.Paste")
			(net "PWRGD_PVDDIO_P0_R")
		)
		(pad "21" smd rect
			(at 0.999998 2.875026 270)
			(size 0.1778 0.6604)
			(layers "F.Cu" "F.Mask" "F.Paste")
			(net "SVID_PVDDCR_CPU1_P0_SVD_R1")
		)
		(pad "22" smd rect
			(at 1.400048 2.875026 270)
			(size 0.1778 0.6604)
			(layers "F.Cu" "F.Mask" "F.Paste")
			(net "SVID_PVDDCR_CPU1_P0_SVC_R1")
		)
		(pad "23" smd rect
			(at 1.800098 2.875026 270)
			(size 0.1778 0.6604)
			(layers "F.Cu" "F.Mask" "F.Paste")
			(net "SVID_PVDDCR_CPU1_P0_SVTO_R")
		)
		(pad "24" smd rect
			(at 2.199894 2.875026 270)
			(size 0.1778 0.6604)
			(layers "F.Cu" "F.Mask" "F.Paste")
			(net "SVID_PVDDCR_CPU1_P0_SVTI_R")
		)
		(pad "25" smd rect
			(at 2.875026 2.199894 180)
			(size 0.1778 0.6604)
			(layers "F.Cu" "F.Mask" "F.Paste")
			(net "VSENSE_PVDDCR_CPU1_P0_VSEN0")
		)
		(pad "26" smd rect
			(at 2.875026 1.800098 180)
			(size 0.1778 0.6604)
			(layers "F.Cu" "F.Mask" "F.Paste")
			(net "VSENSE_VSS_SENSE_C_P0")
		)
		(pad "27" smd rect
			(at 2.875026 1.400048 180)
			(size 0.1778 0.6604)
			(layers "F.Cu" "F.Mask" "F.Paste")
			(net "PVDDCR_CPU1_P0_IMON1")
		)
		(pad "28" smd rect
			(at 2.875026 0.999998 180)
			(size 0.1778 0.6604)
			(layers "F.Cu" "F.Mask" "F.Paste")
			(net "PVDDCR_CPU1_P0_IMON2")
		)
		(pad "29" smd rect
			(at 2.875026 0.599948 180)
			(size 0.1778 0.6604)
			(layers "F.Cu" "F.Mask" "F.Paste")
			(net "PVDDCR_CPU1_P0_IMON3")
		)
		(pad "30" smd rect
			(at 2.875026 0.199898 180)
			(size 0.1778 0.6604)
			(layers "F.Cu" "F.Mask" "F.Paste")
			(net "PVDDCR_CPU1_P0_IMON4")
		)
		(pad "31" smd rect
			(at 2.875026 -0.199898 180)
			(size 0.1778 0.6604)
			(layers "F.Cu" "F.Mask" "F.Paste")
			(net "PVDDCR_CPU1_P0_IMON5")
		)
		(pad "32" smd rect
			(at 2.875026 -0.599948 180)
			(size 0.1778 0.6604)
			(layers "F.Cu" "F.Mask" "F.Paste")
			(net "PVDDCR_CPU1_P0_IMON6")
		)
		(pad "33" smd rect
			(at 2.875026 -0.999998 180)
			(size 0.1778 0.6604)
			(layers "F.Cu" "F.Mask" "F.Paste")
			(net "NC_PVDDCR_CPU1_P0_IMON7")
		)
		(pad "34" smd rect
			(at 2.875026 -1.400048 180)
			(size 0.1778 0.6604)
			(layers "F.Cu" "F.Mask" "F.Paste")
			(net "NC_PVDDCR_CPU1_P0_IMON8")
		)
		(pad "35" smd rect
			(at 2.875026 -1.800098 180)
			(size 0.1778 0.6604)
			(layers "F.Cu" "F.Mask" "F.Paste")
			(net "PVDDIO_P0_IMON4")
		)
		(pad "36" smd rect
			(at 2.875026 -2.199894 180)
			(size 0.1778 0.6604)
			(layers "F.Cu" "F.Mask" "F.Paste")
			(net "PVDDIO_P0_IMON3")
		)
		(pad "37" smd rect
			(at 2.199894 -2.875026 270)
			(size 0.1778 0.6604)
			(layers "F.Cu" "F.Mask" "F.Paste")
			(net "PVDDIO_P0_IMON2")
		)
		(pad "38" smd rect
			(at 1.800098 -2.875026 270)
			(size 0.1778 0.6604)
			(layers "F.Cu" "F.Mask" "F.Paste")
			(net "PVDDIO_P0_IMON1")
		)
		(pad "39" smd rect
			(at 1.400048 -2.875026 270)
			(size 0.1778 0.6604)
			(layers "F.Cu" "F.Mask" "F.Paste")
			(net "VSENSE_VSS_SENSE_B_P0")
		)
		(pad "40" smd rect
			(at 0.999998 -2.875026 270)
			(size 0.1778 0.6604)
			(layers "F.Cu" "F.Mask" "F.Paste")
			(net "VSENSE_PVDDIO_P0_VSEN1")
		)
		(pad "41" smd rect
			(at 0.599948 -2.875026 270)
			(size 0.1778 0.6604)
			(layers "F.Cu" "F.Mask" "F.Paste")
			(net "PVDDCR_CPU1_P0_OCP_N_R")
		)
		(pad "42" smd rect
			(at 0.199898 -2.875026 270)
			(size 0.1778 0.6604)
			(layers "F.Cu" "F.Mask" "F.Paste")
			(net "PVDDCR_CPU1_P0_EN1_ADDR_CFG")
		)
		(pad "43" smd rect
			(at -0.199898 -2.875026 270)
			(size 0.1778 0.6604)
			(layers "F.Cu" "F.Mask" "F.Paste")
			(net "PVDDIO_P0_TEMP1")
		)
		(pad "44" smd rect
			(at -0.599948 -2.875026 270)
			(size 0.1778 0.6604)
			(layers "F.Cu" "F.Mask" "F.Paste")
			(net "PVDDCR_CPU1_P0_TEMP0")
		)
		(pad "45" smd rect
			(at -0.999998 -2.875026 270)
			(size 0.1778 0.6604)
			(layers "F.Cu" "F.Mask" "F.Paste")
			(net "PVDDCR_CPU1_P0_VMON")
		)
		(pad "46" smd rect
			(at -1.400048 -2.875026 270)
			(size 0.1778 0.6604)
			(layers "F.Cu" "F.Mask" "F.Paste")
			(net "PVDDCR_CPU1_P0_VINSEN")
		)
		(pad "47" smd rect
			(at -1.800098 -2.875026 270)
			(size 0.1778 0.6604)
			(layers "F.Cu" "F.Mask" "F.Paste")
			(net "PVDDCR_CPU1_P0_VCC")
		)
		(pad "48" smd rect
			(at -2.199894 -2.875026 270)
			(size 0.1778 0.6604)
			(layers "F.Cu" "F.Mask" "F.Paste")
			(net "PVDDCR_CPU1_P0_VCCS")
		)
		(pad "TH" smd rect
			(at 0 0 270)
			(size 4.4196 4.4196)
			(layers "F.Cu" "F.Mask" "F.Paste")
			(net "GND")
		)
		(zone
			(layer "F.Cu")
			(hatch none 0.5)
			(connect_pads
				(clearance 0)
			)
			(min_thickness 0.25)
			(keepout
				(tracks not_allowed)
				(vias allowed)
				(pads allowed)
				(copperpour not_allowed)
				(footprints allowed)
			)
			(placement
				(enabled no)
				(sheetname "")
			)
			(fill
				(thermal_gap 0.5)
				(thermal_bridge_width 0.5)
				(island_removal_mode 0)
			)
			(polygon
				(pts
					(xy 310.1594 -363.174026) (xy 312.628026 -363.174026) (xy 312.628026 -358.185974) (xy 307.639974 -358.185974)
					(xy 307.639974 -363.174026) (xy 310.134 -363.174026) (xy 310.134 -362.9406) (xy 307.8734 -362.9406)
					(xy 307.8734 -358.4194) (xy 312.3946 -358.4194) (xy 312.3946 -362.9406) (xy 310.1594 -362.9406)
				)
			)
		)
	)
	(footprint ""
		(layer "F.Cu")
		(at 140.02512 -31.62681 -90)
		(property "Reference" "C6016"
			(at 0 0 270)
			(layer "F.SilkS")
			(hide yes)
			(effects
				(font
					(size 1.27 1.27)
				)
			)
		)
		(property "Value" ""
			(at 0 0 270)
			(layer "F.Fab")
			(effects
				(font
					(size 1.27 1.27)
				)
			)
		)
		(duplicate_pad_numbers_are_jumpers no)
		(fp_line
			(start 0.40005 0.4064)
			(end -0.40005 0.4064)
			(stroke
				(width 0.1524)
				(type default)
			)
			(layer "F.SilkS")
		)
		(fp_line
			(start -0.6858 0.3048)
			(end -0.6858 -0.3048)
			(stroke
				(width 0.1)
				(type default)
			)
			(layer "F.Fab")
		)
		(fp_line
			(start -0.1016 0.3048)
			(end -0.6858 0.3048)
			(stroke
				(width 0.1)
				(type default)
			)
			(layer "F.Fab")
		)
		(fp_line
			(start 0.1016 0.3048)
			(end 0.1016 0.2794)
			(stroke
				(width 0.1)
				(type default)
			)
			(layer "F.Fab")
		)
		(fp_line
			(start 0.6858 0.3048)
			(end 0.1016 0.3048)
			(stroke
				(width 0.1)
				(type default)
			)
			(layer "F.Fab")
		)
		(fp_line
			(start -0.1016 0.2794)
			(end -0.1016 0.3048)
			(stroke
				(width 0.1)
				(type default)
			)
			(layer "F.Fab")
		)
		(fp_line
			(start 0.1016 0.2794)
			(end -0.1016 0.2794)
			(stroke
				(width 0.1)
				(type default)
			)
			(layer "F.Fab")
		)
		(fp_line
			(start -0.1016 -0.2794)
			(end 0.1016 -0.2794)
			(stroke
				(width 0.1)
				(type default)
			)
			(layer "F.Fab")
		)
		(fp_line
			(start 0.1016 -0.2794)
			(end 0.1016 -0.3048)
			(stroke
				(width 0.1)
				(type default)
			)
			(layer "F.Fab")
		)
		(fp_line
			(start -0.6858 -0.3048)
			(end -0.1016 -0.3048)
			(stroke
				(width 0.1)
				(type default)
			)
			(layer "F.Fab")
		)
		(fp_line
			(start -0.1016 -0.3048)
			(end -0.1016 -0.2794)
			(stroke
				(width 0.1)
				(type default)
			)
			(layer "F.Fab")
		)
		(fp_line
			(start 0.1016 -0.3048)
			(end 0.6858 -0.3048)
			(stroke
				(width 0.1)
				(type default)
			)
			(layer "F.Fab")
		)
		(fp_line
			(start 0.6858 -0.3048)
			(end 0.6858 0.3048)
			(stroke
				(width 0.1)
				(type default)
			)
			(layer "F.Fab")
		)
		(pad "1" smd rect
			(at -0.40005 0 90)
			(size 0.4572 0.508)
			(layers "F.Cu" "F.Mask" "F.Paste")
			(net "USB3_CPU0_BMC_RX_HUB1_DN")
		)
		(pad "2" smd rect
			(at 0.40005 0 90)
			(size 0.4572 0.508)
			(layers "F.Cu" "F.Mask" "F.Paste")
			(net "USB3_CPU0_BMC_RX_HUB_C_DN")
		)
	)
	(footprint ""
		(layer "F.Cu")
		(at 93.996256 -61.248544 90)
		(property "Reference" "PR3829"
			(at 0 0 90)
			(layer "F.SilkS")
			(hide yes)
			(effects
				(font
					(size 1.27 1.27)
				)
			)
		)
		(property "Value" ""
			(at 0 0 90)
			(layer "F.Fab")
			(effects
				(font
					(size 1.27 1.27)
				)
			)
		)
		(duplicate_pad_numbers_are_jumpers no)
		(fp_line
			(start 0.7874 -0.4064)
			(end 0.7874 0.4064)
			(stroke
				(width 0.1524)
				(type default)
			)
			(layer "F.SilkS")
		)
		(fp_line
			(start -0.7874 -0.4064)
			(end 0.7874 -0.4064)
			(stroke
				(width 0.1524)
				(type default)
			)
			(layer "F.SilkS")
		)
		(fp_line
			(start 0.7874 0.4064)
			(end -0.7874 0.4064)
			(stroke
				(width 0.1524)
				(type default)
			)
			(layer "F.SilkS")
		)
		(fp_line
			(start -0.7874 0.4064)
			(end -0.7874 -0.4064)
			(stroke
				(width 0.1524)
				(type default)
			)
			(layer "F.SilkS")
		)
		(fp_line
			(start -0.12065 -0.305054)
			(end -0.12065 -0.2794)
			(stroke
				(width 0.1)
				(type default)
			)
			(layer "F.Fab")
		)
		(fp_line
			(start -0.67945 -0.305054)
			(end -0.12065 -0.305054)
			(stroke
				(width 0.1)
				(type default)
			)
			(layer "F.Fab")
		)
		(fp_line
			(start 0.67945 -0.3048)
			(end 0.67945 0.3048)
			(stroke
				(width 0.1)
				(type default)
			)
			(layer "F.Fab")
		)
		(fp_line
			(start 0.12065 -0.3048)
			(end 0.67945 -0.3048)
			(stroke
				(width 0.1)
				(type default)
			)
			(layer "F.Fab")
		)
		(fp_line
			(start 0.12065 -0.2794)
			(end 0.12065 -0.3048)
			(stroke
				(width 0.1)
				(type default)
			)
			(layer "F.Fab")
		)
		(fp_line
			(start -0.12065 -0.2794)
			(end 0.12065 -0.2794)
			(stroke
				(width 0.1)
				(type default)
			)
			(layer "F.Fab")
		)
		(fp_line
			(start 0.120396 0.2794)
			(end -0.12065 0.2794)
			(stroke
				(width 0.1)
				(type default)
			)
			(layer "F.Fab")
		)
		(fp_line
			(start -0.12065 0.2794)
			(end -0.12065 0.3048)
			(stroke
				(width 0.1)
				(type default)
			)
			(layer "F.Fab")
		)
		(fp_line
			(start 0.67945 0.3048)
			(end 0.120396 0.3048)
			(stroke
				(width 0.1)
				(type default)
			)
			(layer "F.Fab")
		)
		(fp_line
			(start 0.120396 0.3048)
			(end 0.120396 0.2794)
			(stroke
				(width 0.1)
				(type default)
			)
			(layer "F.Fab")
		)
		(fp_line
			(start -0.12065 0.3048)
			(end -0.67945 0.3048)
			(stroke
				(width 0.1)
				(type default)
			)
			(layer "F.Fab")
		)
		(fp_line
			(start -0.67945 0.3048)
			(end -0.67945 -0.305054)
			(stroke
				(width 0.1)
				(type default)
			)
			(layer "F.Fab")
		)
		(pad "1" smd circle
			(at -0.40005 0 90)
			(size 0 0)
			(layers "F.Cu" "F.Mask" "F.Paste")
			(net "P3V3_OCP_UV_2")
		)
		(pad "2" smd circle
			(at 0.40005 0 90)
			(size 0 0)
			(layers "F.Cu" "F.Mask" "F.Paste")
			(net "P3V3_OCP_OV_2")
		)
	)
)
